#ISCELL
  pure_quanta quanta_title_block_c *
  *
#ISCELL
  standard offpage *
  page317_i1
#ISCELL
  standard offpage *
  page317_i10
#ISCELL
  standard offpage *
  page317_i12
#ISCELL
  standard offpage *
  page317_i13
#ISCELL
  standard offpage *
  page317_i14
#ISCELL
  standard offpage *
  page317_i15
#ISCELL
  standard offpage *
  page317_i16
#ISCELL
  standard offpage *
  page317_i17
#ISCELL
  standard offpage *
  page317_i18
#ISCELL
  logical_power universal_gnd *
  page317_i19
#ISCELL
  standard offpage *
  page317_i2
#ISCELL
  standard offpage *
  page317_i20
#ISCELL
  standard offpage *
  page317_i21
#ISCELL
  standard offpage *
  page317_i22
#ISCELL
  standard offpage *
  page317_i23
#ISCELL
  standard offpage *
  page317_i24
#ISCELL
  standard offpage *
  page317_i27
#ISCELL
  standard offpage *
  page317_i28
#ISCELL
  standard offpage *
  page317_i29
#ISCELL
  standard offpage *
  page317_i3
#ISCELL
  standard offpage *
  page317_i30
#ISCELL
  standard offpage *
  page317_i31
#ISCELL
  standard offpage *
  page317_i32
#ISCELL
  standard offpage *
  page317_i33
#ISCELL
  standard offpage *
  page317_i34
#ISCELL
  standard offpage *
  page317_i35
#ISCELL
  standard offpage *
  page317_i36
#ISCELL
  standard offpage *
  page317_i37
#CELL
  pure_quanta conn112_10137002101lf *
  page317_i38
#ISCELL
  standard offpage *
  page317_i39
#ISCELL
  standard offpage *
  page317_i4
#ISCELL
  standard offpage *
  page317_i40
#ISCELL
  standard offpage *
  page317_i41
#ISCELL
  standard offpage *
  page317_i42
#ISCELL
  standard offpage *
  page317_i43
#ISCELL
  standard offpage *
  page317_i44
#ISCELL
  standard offpage *
  page317_i45
#ISCELL
  standard offpage *
  page317_i46
#ISCELL
  standard offpage *
  page317_i49
#ISCELL
  standard offpage *
  page317_i5
#ISCELL
  standard offpage *
  page317_i50
#ISCELL
  standard offpage *
  page317_i51
#ISCELL
  standard offpage *
  page317_i52
#ISCELL
  standard offpage *
  page317_i53
#ISCELL
  standard offpage *
  page317_i54
#ISCELL
  standard offpage *
  page317_i55
#ISCELL
  standard offpage *
  page317_i56
#ISCELL
  logical_power universal_gnd *
  page317_i57
#CELL
  pure_quanta conn112_10137002101lf *
  page317_i58
#ISCELL
  standard offpage *
  page317_i59
#ISCELL
  standard offpage *
  page317_i6
#ISCELL
  standard offpage *
  page317_i60
#ISCELL
  standard offpage *
  page317_i61
#ISCELL
  standard offpage *
  page317_i62
#ISCELL
  standard offpage *
  page317_i63
#ISCELL
  standard offpage *
  page317_i64
#ISCELL
  standard offpage *
  page317_i65
#ISCELL
  standard offpage *
  page317_i66
#ISCELL
  standard offpage *
  page317_i69
#ISCELL
  standard offpage *
  page317_i70
#ISCELL
  standard offpage *
  page317_i71
#ISCELL
  standard offpage *
  page317_i72
#ISCELL
  standard offpage *
  page317_i73
#ISCELL
  standard offpage *
  page317_i74
#ISCELL
  standard offpage *
  page317_i75
#ISCELL
  standard offpage *
  page317_i76
#ISCELL
  standard offpage *
  page317_i77
#ISCELL
  standard offpage *
  page317_i78
#ISCELL
  standard offpage *
  page317_i79
#ISCELL
  standard offpage *
  page317_i8
#ISCELL
  standard offpage *
  page317_i9
